# S9S_MB_2U (Grand Teton) — schematic netlist excerpt (pin names and nets, part order shuffled) for the footprints in the layout excerpt that follows; sources: Cadence DE-HDL packaged netlist, KiCad conversion of 03242023_DA0F0TMBIJ0_F0T_Motherboard_J_brd_V01_OCP.brd

R4169  Q_RES  4.7K 5% CHIP  pkg 0402LF  page 145 : A = P3V3_AUX ; B = GPU_3V3IO_RSVD3_ISO
PC2206  Q_CAP  0.1UF 25V 10% X7R  pkg 0402  page 193 : A = P12V_E1S_0 ; B = GND
C839  Q_CAP_DIFFBUS  DIFF BUS_0.22UF 6.3V 20% X6S  pkg C0201  page 174 : \1\ = P5E_CPU0_PE1_TX_C_DP<15> ; \2\ = P5E_CPU0_PE1_TX_DP<15>

(kicad_pcb
	(version 20260206)
	(generator "pcbnew")
	(generator_version "10.0")
	(general
		(thickness 1.6)
		(legacy_teardrops no)
	)
	(paper "A4")
	(title_block
		(title "03242023_DA0F0TMBIJ0_F0T_Motherboard_J_brd_V01_OCP.brd")
		(comment 1 "Grand Teton / footprints 2850-2852 of 6105")
	)
	(layers
		(0 "F.Cu" signal "TOP")
		(4 "In1.Cu" signal "GND")
		(6 "In2.Cu" signal "IN1")
		(8 "In3.Cu" signal "GND1")
		(10 "In4.Cu" signal "IN2")
		(12 "In5.Cu" signal "GND2")
		(14 "In6.Cu" signal "IN3")
		(16 "In7.Cu" signal "GND3")
		(18 "In8.Cu" signal "VCC")
		(20 "In9.Cu" signal "VCC1")
		(22 "In10.Cu" signal "GND4")
		(24 "In11.Cu" signal "IN4")
		(26 "In12.Cu" signal "GND5")
		(28 "In13.Cu" signal "IN5")
		(30 "In14.Cu" signal "GND6")
		(32 "In15.Cu" signal "IN6")
		(34 "In16.Cu" signal "GND7")
		(2 "B.Cu" signal "BOTTOM")
		(9 "F.Adhes" user "F.Adhesive")
		(11 "B.Adhes" user "B.Adhesive")
		(13 "F.Paste" user "Package Geometry/Pastemask Top")
		(15 "B.Paste" user "Package Geometry/Pastemask Bottom")
		(5 "F.SilkS" user "Ref Des/Silkscreen Top")
		(7 "B.SilkS" user "Ref Des/Silkscreen Bottom")
		(1 "F.Mask" user "Board Geometry/Soldermask Top")
		(3 "B.Mask" user "Board Geometry/Soldermask Bottom")
		(17 "Dwgs.User" user "User.Drawings")
		(19 "Cmts.User" user "User.Comments")
		(21 "Eco1.User" user "User.Eco1")
		(23 "Eco2.User" user "User.Eco2")
		(25 "Edge.Cuts" user "Board Geometry/Outline")
		(27 "Margin" user)
		(31 "F.CrtYd" user "Package Geometry/Place Bound Top")
		(29 "B.CrtYd" user "Package Geometry/Place Bound Bottom")
		(35 "F.Fab" user "Ref Des/Assembly Top")
		(33 "B.Fab" user "Ref Des/Assembly Bottom")
	)
	(footprint ""
		(layer "F.Cu")
		(at 360.444542 -389.19277)
		(property "Reference" "R4169"
			(at 0 0 0)
			(layer "F.SilkS")
			(hide yes)
			(effects
				(font
					(size 1.27 1.27)
				)
			)
		)
		(property "Value" ""
			(at 0 0 0)
			(layer "F.Fab")
			(effects
				(font
					(size 1.27 1.27)
				)
			)
		)
		(duplicate_pad_numbers_are_jumpers no)
		(fp_line
			(start -0.7874 -0.4064)
			(end 0.7874 -0.4064)
			(stroke
				(width 0.1524)
				(type default)
			)
			(layer "F.SilkS")
		)
		(fp_line
			(start -0.7874 0.4064)
			(end -0.7874 -0.4064)
			(stroke
				(width 0.1524)
				(type default)
			)
			(layer "F.SilkS")
		)
		(fp_line
			(start 0.7874 -0.4064)
			(end 0.7874 0.4064)
			(stroke
				(width 0.1524)
				(type default)
			)
			(layer "F.SilkS")
		)
		(fp_line
			(start 0.7874 0.4064)
			(end -0.7874 0.4064)
			(stroke
				(width 0.1524)
				(type default)
			)
			(layer "F.SilkS")
		)
		(fp_line
			(start -0.67945 -0.305054)
			(end -0.12065 -0.305054)
			(stroke
				(width 0.1)
				(type default)
			)
			(layer "F.Fab")
		)
		(fp_line
			(start -0.67945 0.3048)
			(end -0.67945 -0.305054)
			(stroke
				(width 0.1)
				(type default)
			)
			(layer "F.Fab")
		)
		(fp_line
			(start -0.12065 -0.305054)
			(end -0.12065 -0.2794)
			(stroke
				(width 0.1)
				(type default)
			)
			(layer "F.Fab")
		)
		(fp_line
			(start -0.12065 -0.2794)
			(end 0.12065 -0.2794)
			(stroke
				(width 0.1)
				(type default)
			)
			(layer "F.Fab")
		)
		(fp_line
			(start -0.12065 0.2794)
			(end -0.12065 0.3048)
			(stroke
				(width 0.1)
				(type default)
			)
			(layer "F.Fab")
		)
		(fp_line
			(start -0.12065 0.3048)
			(end -0.67945 0.3048)
			(stroke
				(width 0.1)
				(type default)
			)
			(layer "F.Fab")
		)
		(fp_line
			(start 0.120396 0.2794)
			(end -0.12065 0.2794)
			(stroke
				(width 0.1)
				(type default)
			)
			(layer "F.Fab")
		)
		(fp_line
			(start 0.120396 0.3048)
			(end 0.120396 0.2794)
			(stroke
				(width 0.1)
				(type default)
			)
			(layer "F.Fab")
		)
		(fp_line
			(start 0.12065 -0.3048)
			(end 0.67945 -0.3048)
			(stroke
				(width 0.1)
				(type default)
			)
			(layer "F.Fab")
		)
		(fp_line
			(start 0.12065 -0.2794)
			(end 0.12065 -0.3048)
			(stroke
				(width 0.1)
				(type default)
			)
			(layer "F.Fab")
		)
		(fp_line
			(start 0.67945 -0.3048)
			(end 0.67945 0.3048)
			(stroke
				(width 0.1)
				(type default)
			)
			(layer "F.Fab")
		)
		(fp_line
			(start 0.67945 0.3048)
			(end 0.120396 0.3048)
			(stroke
				(width 0.1)
				(type default)
			)
			(layer "F.Fab")
		)
		(pad "1" smd circle
			(at -0.40005 0)
			(size 0 0)
			(layers "F.Cu" "F.Mask" "F.Paste")
			(net "P3V3_AUX")
		)
		(pad "2" smd circle
			(at 0.40005 0)
			(size 0 0)
			(layers "F.Cu" "F.Mask" "F.Paste")
			(net "GPU_3V3IO_RSVD3_ISO")
		)
	)
	(footprint ""
		(layer "F.Cu")
		(at 390.015984 -16.088614 90)
		(property "Reference" "C839"
			(at 0 0 90)
			(layer "F.SilkS")
			(hide yes)
			(effects
				(font
					(size 1.27 1.27)
				)
			)
		)
		(property "Value" ""
			(at 0 0 90)
			(layer "F.Fab")
			(effects
				(font
					(size 1.27 1.27)
				)
			)
		)
		(duplicate_pad_numbers_are_jumpers no)
		(fp_line
			(start 0.299974 -0.150114)
			(end 0.299974 0.150114)
			(stroke
				(width 0.1)
				(type default)
			)
			(layer "F.Fab")
		)
		(fp_line
			(start -0.299974 -0.150114)
			(end 0.299974 -0.150114)
			(stroke
				(width 0.1)
				(type default)
			)
			(layer "F.Fab")
		)
		(fp_line
			(start 0.299974 0.150114)
			(end -0.299974 0.150114)
			(stroke
				(width 0.1)
				(type default)
			)
			(layer "F.Fab")
		)
		(fp_line
			(start -0.299974 0.150114)
			(end -0.299974 -0.150114)
			(stroke
				(width 0.1)
				(type default)
			)
			(layer "F.Fab")
		)
		(pad "1" smd rect
			(at -0.2667 0 90)
			(size 0.3048 0.381)
			(layers "F.Cu" "F.Mask" "F.Paste")
			(net "P5E_CPU0_PE1_TX_C_DP<15>")
		)
		(pad "2" smd rect
			(at 0.2667 0 90)
			(size 0.3048 0.381)
			(layers "F.Cu" "F.Mask" "F.Paste")
			(net "P5E_CPU0_PE1_TX_DP<15>")
		)
	)
	(footprint ""
		(layer "F.Cu")
		(at 251.16409 -48.121062 -90)
		(property "Reference" "PC2206"
			(at 0 0 270)
			(layer "F.SilkS")
			(hide yes)
			(effects
				(font
					(size 1.27 1.27)
				)
			)
		)
		(property "Value" ""
			(at 0 0 270)
			(layer "F.Fab")
			(effects
				(font
					(size 1.27 1.27)
				)
			)
		)
		(duplicate_pad_numbers_are_jumpers no)
		(fp_line
			(start -0.7874 0.4064)
			(end -0.7874 -0.4064)
			(stroke
				(width 0.1524)
				(type default)
			)
			(layer "F.SilkS")
		)
		(fp_line
			(start 0.7874 0.4064)
			(end -0.7874 0.4064)
			(stroke
				(width 0.1524)
				(type default)
			)
			(layer "F.SilkS")
		)
		(fp_line
			(start -0.7874 -0.4064)
			(end 0.7874 -0.4064)
			(stroke
				(width 0.1524)
				(type default)
			)
			(layer "F.SilkS")
		)
		(fp_line
			(start 0.7874 -0.4064)
			(end 0.7874 0.4064)
			(stroke
				(width 0.1524)
				(type default)
			)
			(layer "F.SilkS")
		)
		(fp_line
			(start -0.67945 0.3048)
			(end -0.67945 -0.305054)
			(stroke
				(width 0.1)
				(type default)
			)
			(layer "F.Fab")
		)
		(fp_line
			(start -0.12065 0.3048)
			(end -0.67945 0.3048)
			(stroke
				(width 0.1)
				(type default)
			)
			(layer "F.Fab")
		)
		(fp_line
			(start 0.120396 0.3048)
			(end 0.120396 0.2794)
			(stroke
				(width 0.1)
				(type default)
			)
			(layer "F.Fab")
		)
		(fp_line
			(start 0.67945 0.3048)
			(end 0.120396 0.3048)
			(stroke
				(width 0.1)
				(type default)
			)
			(layer "F.Fab")
		)
		(fp_line
			(start -0.12065 0.2794)
			(end -0.12065 0.3048)
			(stroke
				(width 0.1)
				(type default)
			)
			(layer "F.Fab")
		)
		(fp_line
			(start 0.120396 0.2794)
			(end -0.12065 0.2794)
			(stroke
				(width 0.1)
				(type default)
			)
			(layer "F.Fab")
		)
		(fp_line
			(start -0.12065 -0.2794)
			(end 0.12065 -0.2794)
			(stroke
				(width 0.1)
				(type default)
			)
			(layer "F.Fab")
		)
		(fp_line
			(start 0.12065 -0.2794)
			(end 0.12065 -0.3048)
			(stroke
				(width 0.1)
				(type default)
			)
			(layer "F.Fab")
		)
		(fp_line
			(start 0.12065 -0.3048)
			(end 0.67945 -0.3048)
			(stroke
				(width 0.1)
				(type default)
			)
			(layer "F.Fab")
		)
		(fp_line
			(start 0.67945 -0.3048)
			(end 0.67945 0.3048)
			(stroke
				(width 0.1)
				(type default)
			)
			(layer "F.Fab")
		)
		(fp_line
			(start -0.67945 -0.305054)
			(end -0.12065 -0.305054)
			(stroke
				(width 0.1)
				(type default)
			)
			(layer "F.Fab")
		)
		(fp_line
			(start -0.12065 -0.305054)
			(end -0.12065 -0.2794)
			(stroke
				(width 0.1)
				(type default)
			)
			(layer "F.Fab")
		)
		(pad "1" smd circle
			(at -0.40005 0 270)
			(size 0 0)
			(layers "F.Cu" "F.Mask" "F.Paste")
			(net "P12V_E1S_0")
		)
		(pad "2" smd circle
			(at 0.40005 0 270)
			(size 0 0)
			(layers "F.Cu" "F.Mask" "F.Paste")
			(net "GND")
		)
	)
)
